#ISCELL
  pure_quanta quanta_title_block_c *
  *
#CELL
  pure_quanta socket4677_azif0045p001c01cs *
  page69_i1
#ISCELL
  logical_power vcc_core *
  page69_i2
#ISCELL
  logical_power vcc_core *
  page69_i3
